(kicad_pcb
	(version 20260206)
	(generator "pcbnew")
	(generator_version "10.0")
	(general
		(thickness 1.6)
		(legacy_teardrops no)
	)
	(paper "A4")
	(title_block
		(title "v1-chassis-manager — T6M_CM_d_v01_1031_1645.brd")
		(comment 1 "Open CloudServer (Microsoft) / footprints 726-735 of 2512")
	)
	(layers
		(0 "F.Cu" signal "TOP")
		(4 "In1.Cu" signal "GND1")
		(6 "In2.Cu" signal "IN1")
		(8 "In3.Cu" signal "VCC1")
		(10 "In4.Cu" signal "VCC2")
		(12 "In5.Cu" signal "GND2")
		(14 "In6.Cu" signal "IN2")
		(16 "In7.Cu" signal "IN3")
		(18 "In8.Cu" signal "GND3")
		(2 "B.Cu" signal "BOTTOM")
		(9 "F.Adhes" user "F.Adhesive")
		(11 "B.Adhes" user "B.Adhesive")
		(13 "F.Paste" user "Package Geometry/Pastemask Top")
		(15 "B.Paste" user "Package Geometry/Pastemask Bottom")
		(5 "F.SilkS" user "Ref Des/Silkscreen Top")
		(7 "B.SilkS" user "Ref Des/Silkscreen Bottom")
		(1 "F.Mask" user "Board Geometry/Soldermask Top")
		(3 "B.Mask" user "Board Geometry/Soldermask Bottom")
		(17 "Dwgs.User" user "User.Drawings")
		(19 "Cmts.User" user "User.Comments")
		(21 "Eco1.User" user "User.Eco1")
		(23 "Eco2.User" user "User.Eco2")
		(25 "Edge.Cuts" user "Board Geometry/Outline")
		(27 "Margin" user)
		(31 "F.CrtYd" user "Package Geometry/Place Bound Top")
		(29 "B.CrtYd" user "Package Geometry/Place Bound Bottom")
		(35 "F.Fab" user "Ref Des/Assembly Top")
		(33 "B.Fab" user "Ref Des/Assembly Bottom")
	)
	(footprint ""
		(layer "F.Cu")
		(at 12.949174 -16.260572 -90)
		(property "Reference" "R651"
			(at 1.500124 6.253734 90)
			(unlocked yes)
			(layer "F.SilkS")
			(effects
				(font
					(size 0.7874 0.5842)
					(thickness 0.1524)
				)
				(justify left)
			)
		)
		(property "Value" ""
			(at 0 0 270)
			(layer "F.Fab")
			(effects
				(font
					(size 1.27 1.27)
				)
			)
		)
		(duplicate_pad_numbers_are_jumpers no)
		(fp_line
			(start -0.7874 0.4064)
			(end -0.7874 -0.4064)
			(stroke
				(width 0.1524)
				(type default)
			)
			(layer "F.SilkS")
		)
		(fp_line
			(start 0.7874 0.4064)
			(end -0.7874 0.4064)
			(stroke
				(width 0.1524)
				(type default)
			)
			(layer "F.SilkS")
		)
		(fp_line
			(start -0.7874 -0.4064)
			(end 0.7874 -0.4064)
			(stroke
				(width 0.1524)
				(type default)
			)
			(layer "F.SilkS")
		)
		(fp_line
			(start 0.7874 -0.4064)
			(end 0.7874 0.4064)
			(stroke
				(width 0.1524)
				(type default)
			)
			(layer "F.SilkS")
		)
		(fp_poly
			(pts
				(xy -0.508 0.2794) (xy -0.508 0.2286) (xy -0.635 0.2286) (xy -0.635 -0.254) (xy -0.5334 -0.254)
				(xy -0.5334 -0.2794) (xy 0.5334 -0.2794) (xy 0.5334 -0.254) (xy 0.635 -0.254) (xy 0.635 0.254) (xy 0.5334 0.254)
				(xy 0.5334 0.2794)
			)
			(stroke
				(width 0)
				(type default)
			)
			(fill no)
			(layer "F.CrtYd")
		)
		(pad "1" smd rect
			(at 0.40005 0 270)
			(size 0.4572 0.508)
			(layers "F.Cu" "F.Mask" "F.Paste")
			(net "P3V3_NODE1")
		)
		(pad "2" smd rect
			(at -0.40005 0 270)
			(size 0.4572 0.508)
			(layers "F.Cu" "F.Mask" "F.Paste")
			(net "N54251487")
		)
	)
	(footprint ""
		(layer "F.Cu")
		(at 186.202828 -116.961666 180)
		(property "Reference" "R1246"
			(at -1.249172 0.994664 0)
			(unlocked yes)
			(layer "F.SilkS")
			(effects
				(font
					(size 0.7874 0.5842)
					(thickness 0.1524)
				)
				(justify left)
			)
		)
		(property "Value" ""
			(at 0 0 180)
			(layer "F.Fab")
			(effects
				(font
					(size 1.27 1.27)
				)
			)
		)
		(duplicate_pad_numbers_are_jumpers no)
		(fp_line
			(start 0.7874 0.4064)
			(end -0.7874 0.4064)
			(stroke
				(width 0.1524)
				(type default)
			)
			(layer "F.SilkS")
		)
		(fp_line
			(start 0.7874 -0.4064)
			(end 0.7874 0.4064)
			(stroke
				(width 0.1524)
				(type default)
			)
			(layer "F.SilkS")
		)
		(fp_line
			(start -0.7874 0.4064)
			(end -0.7874 -0.4064)
			(stroke
				(width 0.1524)
				(type default)
			)
			(layer "F.SilkS")
		)
		(fp_line
			(start -0.7874 -0.4064)
			(end 0.7874 -0.4064)
			(stroke
				(width 0.1524)
				(type default)
			)
			(layer "F.SilkS")
		)
		(fp_poly
			(pts
				(xy -0.508 0.2794) (xy -0.508 0.2286) (xy -0.635 0.2286) (xy -0.635 -0.254) (xy -0.5334 -0.254)
				(xy -0.5334 -0.2794) (xy 0.5334 -0.2794) (xy 0.5334 -0.254) (xy 0.635 -0.254) (xy 0.635 0.254) (xy 0.5334 0.254)
				(xy 0.5334 0.2794)
			)
			(stroke
				(width 0)
				(type default)
			)
			(fill no)
			(layer "F.CrtYd")
		)
		(pad "1" smd rect
			(at 0.40005 0 180)
			(size 0.4572 0.508)
			(layers "F.Cu" "F.Mask" "F.Paste")
			(net "PWRGD_NODE1_P5V_STB_PG_CPLD")
		)
		(pad "2" smd rect
			(at -0.40005 0 180)
			(size 0.4572 0.508)
			(layers "F.Cu" "F.Mask" "F.Paste")
			(net "PWRGD_NODE1_P5V_STB_PG")
		)
	)
	(footprint ""
		(layer "F.Cu")
		(at 18.381472 -74.207878 90)
		(property "Reference" "C498"
			(at 1.69672 -0.072898 90)
			(unlocked yes)
			(layer "F.SilkS")
			(effects
				(font
					(size 0.7874 0.5842)
					(thickness 0.1524)
				)
				(justify left)
			)
		)
		(property "Value" ""
			(at 0 0 90)
			(layer "F.Fab")
			(effects
				(font
					(size 1.27 1.27)
				)
			)
		)
		(duplicate_pad_numbers_are_jumpers no)
		(fp_line
			(start 0.7874 -0.4064)
			(end 0.7874 0.4064)
			(stroke
				(width 0.1524)
				(type default)
			)
			(layer "F.SilkS")
		)
		(fp_line
			(start -0.7874 -0.4064)
			(end 0.7874 -0.4064)
			(stroke
				(width 0.1524)
				(type default)
			)
			(layer "F.SilkS")
		)
		(fp_line
			(start 0 0.381)
			(end 0 -0.381)
			(stroke
				(width 0.1524)
				(type default)
			)
			(layer "F.SilkS")
		)
		(fp_line
			(start 0.7874 0.4064)
			(end -0.7874 0.4064)
			(stroke
				(width 0.1524)
				(type default)
			)
			(layer "F.SilkS")
		)
		(fp_line
			(start -0.7874 0.4064)
			(end -0.7874 -0.4064)
			(stroke
				(width 0.1524)
				(type default)
			)
			(layer "F.SilkS")
		)
		(fp_poly
			(pts
				(xy -0.5334 0.254) (xy -0.635 0.254) (xy -0.635 0.2286) (xy -0.635 -0.254) (xy -0.5334 -0.254) (xy -0.5334 -0.2794)
				(xy 0.5334 -0.2794) (xy 0.5334 -0.254) (xy 0.635 -0.254) (xy 0.635 0.254) (xy 0.5334 0.254) (xy 0.5334 0.2794)
				(xy -0.508 0.2794) (xy -0.5334 0.2794)
			)
			(stroke
				(width 0)
				(type default)
			)
			(fill no)
			(layer "F.CrtYd")
		)
		(pad "1" smd rect
			(at 0.40005 0 90)
			(size 0.4572 0.508)
			(layers "F.Cu" "F.Mask" "F.Paste")
			(net "VCC5_CRTXX")
		)
		(pad "2" smd rect
			(at -0.40005 0 90)
			(size 0.4572 0.508)
			(layers "F.Cu" "F.Mask" "F.Paste")
			(net "GND")
		)
	)
	(footprint ""
		(layer "F.Cu")
		(at 123.70816 -170.587416)
		(property "Reference" "R674"
			(at 30.127448 47.889922 0)
			(unlocked yes)
			(layer "F.SilkS")
			(effects
				(font
					(size 0.7874 0.5842)
					(thickness 0.1524)
				)
				(justify left)
			)
		)
		(property "Value" ""
			(at 0 0 0)
			(layer "F.Fab")
			(effects
				(font
					(size 1.27 1.27)
				)
			)
		)
		(duplicate_pad_numbers_are_jumpers no)
		(fp_line
			(start -0.7874 -0.4064)
			(end 0.7874 -0.4064)
			(stroke
				(width 0.1524)
				(type default)
			)
			(layer "F.SilkS")
		)
		(fp_line
			(start -0.7874 0.4064)
			(end -0.7874 -0.4064)
			(stroke
				(width 0.1524)
				(type default)
			)
			(layer "F.SilkS")
		)
		(fp_line
			(start 0.7874 -0.4064)
			(end 0.7874 0.4064)
			(stroke
				(width 0.1524)
				(type default)
			)
			(layer "F.SilkS")
		)
		(fp_line
			(start 0.7874 0.4064)
			(end -0.7874 0.4064)
			(stroke
				(width 0.1524)
				(type default)
			)
			(layer "F.SilkS")
		)
		(fp_poly
			(pts
				(xy -0.508 0.2794) (xy -0.508 0.2286) (xy -0.635 0.2286) (xy -0.635 -0.254) (xy -0.5334 -0.254)
				(xy -0.5334 -0.2794) (xy 0.5334 -0.2794) (xy 0.5334 -0.254) (xy 0.635 -0.254) (xy 0.635 0.254) (xy 0.5334 0.254)
				(xy 0.5334 0.2794)
			)
			(stroke
				(width 0)
				(type default)
			)
			(fill no)
			(layer "F.CrtYd")
		)
		(pad "1" smd rect
			(at 0.40005 0)
			(size 0.4572 0.508)
			(layers "F.Cu" "F.Mask" "F.Paste")
			(net "P3V3_NODE1")
		)
		(pad "2" smd rect
			(at -0.40005 0)
			(size 0.4572 0.508)
			(layers "F.Cu" "F.Mask" "F.Paste")
			(net "PU_I2C_SDA4")
		)
	)
	(footprint ""
		(layer "F.Cu")
		(at 42.252646 -113.038636 180)
		(property "Reference" "PR7"
			(at 1.472692 4.630928 0)
			(unlocked yes)
			(layer "F.SilkS")
			(effects
				(font
					(size 0.7874 0.5842)
					(thickness 0.1524)
				)
				(justify left)
			)
		)
		(property "Value" ""
			(at 0 0 180)
			(layer "F.Fab")
			(effects
				(font
					(size 1.27 1.27)
				)
			)
		)
		(duplicate_pad_numbers_are_jumpers no)
		(fp_line
			(start 0.7874 0.4064)
			(end -0.7874 0.4064)
			(stroke
				(width 0.1524)
				(type default)
			)
			(layer "F.SilkS")
		)
		(fp_line
			(start 0.7874 -0.4064)
			(end 0.7874 0.4064)
			(stroke
				(width 0.1524)
				(type default)
			)
			(layer "F.SilkS")
		)
		(fp_line
			(start -0.7874 0.4064)
			(end -0.7874 -0.4064)
			(stroke
				(width 0.1524)
				(type default)
			)
			(layer "F.SilkS")
		)
		(fp_line
			(start -0.7874 -0.4064)
			(end 0.7874 -0.4064)
			(stroke
				(width 0.1524)
				(type default)
			)
			(layer "F.SilkS")
		)
		(fp_poly
			(pts
				(xy -0.508 0.2794) (xy -0.508 0.2286) (xy -0.635 0.2286) (xy -0.635 -0.254) (xy -0.5334 -0.254)
				(xy -0.5334 -0.2794) (xy 0.5334 -0.2794) (xy 0.5334 -0.254) (xy 0.635 -0.254) (xy 0.635 0.254) (xy 0.5334 0.254)
				(xy 0.5334 0.2794)
			)
			(stroke
				(width 0)
				(type default)
			)
			(fill no)
			(layer "F.CrtYd")
		)
		(pad "1" smd rect
			(at 0.40005 0 180)
			(size 0.4572 0.508)
			(layers "F.Cu" "F.Mask" "F.Paste")
			(net "P3V3_STB_NODE1_FB")
		)
		(pad "2" smd rect
			(at -0.40005 0 180)
			(size 0.4572 0.508)
			(layers "F.Cu" "F.Mask" "F.Paste")
			(net "P3V3_STB_NODE1")
		)
	)
	(footprint ""
		(layer "F.Cu")
		(at 137.287 -51.435 -90)
		(property "Reference" "R1155"
			(at -16.3322 -30.68447 90)
			(unlocked yes)
			(layer "F.SilkS")
			(effects
				(font
					(size 0.7874 0.5842)
					(thickness 0.1524)
				)
				(justify left)
			)
		)
		(property "Value" ""
			(at 0 0 270)
			(layer "F.Fab")
			(effects
				(font
					(size 1.27 1.27)
				)
			)
		)
		(duplicate_pad_numbers_are_jumpers no)
		(fp_line
			(start -0.7874 0.4064)
			(end -0.7874 -0.4064)
			(stroke
				(width 0.1524)
				(type default)
			)
			(layer "F.SilkS")
		)
		(fp_line
			(start 0.7874 0.4064)
			(end -0.7874 0.4064)
			(stroke
				(width 0.1524)
				(type default)
			)
			(layer "F.SilkS")
		)
		(fp_line
			(start -0.7874 -0.4064)
			(end 0.7874 -0.4064)
			(stroke
				(width 0.1524)
				(type default)
			)
			(layer "F.SilkS")
		)
		(fp_line
			(start 0.7874 -0.4064)
			(end 0.7874 0.4064)
			(stroke
				(width 0.1524)
				(type default)
			)
			(layer "F.SilkS")
		)
		(fp_poly
			(pts
				(xy -0.508 0.2794) (xy -0.508 0.2286) (xy -0.635 0.2286) (xy -0.635 -0.254) (xy -0.5334 -0.254)
				(xy -0.5334 -0.2794) (xy 0.5334 -0.2794) (xy 0.5334 -0.254) (xy 0.635 -0.254) (xy 0.635 0.254) (xy 0.5334 0.254)
				(xy 0.5334 0.2794)
			)
			(stroke
				(width 0)
				(type default)
			)
			(fill no)
			(layer "F.CrtYd")
		)
		(pad "1" smd rect
			(at 0.40005 0 270)
			(size 0.4572 0.508)
			(layers "F.Cu" "F.Mask" "F.Paste")
			(net "UART_DTR_P3_R_N")
		)
		(pad "2" smd rect
			(at -0.40005 0 270)
			(size 0.4572 0.508)
			(layers "F.Cu" "F.Mask" "F.Paste")
			(net "UART_DTR_P3_N")
		)
	)
	(footprint ""
		(layer "F.Cu")
		(at 21.913342 -53.302408 90)
		(property "Reference" "U48"
			(at -2.97942 13.753338 0)
			(unlocked yes)
			(layer "F.SilkS")
			(effects
				(font
					(size 0.7874 0.5842)
					(thickness 0.1524)
				)
			)
		)
		(property "Value" ""
			(at 0 0 90)
			(layer "F.Fab")
			(effects
				(font
					(size 1.27 1.27)
				)
			)
		)
		(duplicate_pad_numbers_are_jumpers no)
		(fp_line
			(start 1.651 -1.905)
			(end 1.651 1.905)
			(stroke
				(width 0.1524)
				(type default)
			)
			(layer "F.SilkS")
		)
		(fp_line
			(start -1.651 -1.905)
			(end 1.651 -1.905)
			(stroke
				(width 0.1524)
				(type default)
			)
			(layer "F.SilkS")
		)
		(fp_line
			(start 1.651 1.905)
			(end -1.651 1.905)
			(stroke
				(width 0.1524)
				(type default)
			)
			(layer "F.SilkS")
		)
		(fp_line
			(start -1.651 1.905)
			(end -1.651 -1.905)
			(stroke
				(width 0.1524)
				(type default)
			)
			(layer "F.SilkS")
		)
		(fp_poly
			(pts
				(xy -1.524 0.7112) (xy -1.524 1.7526) (xy -0.508 1.7526) (xy -0.508 0.6985) (xy 0.508 0.6985) (xy 0.508 1.7526)
				(xy 1.524 1.7526) (xy 1.524 0.6985) (xy 1.524 -0.6985) (xy 0.508 -0.6985) (xy 0.508 -1.7526) (xy -0.508 -1.7526)
				(xy -0.508 -0.6985) (xy -1.524 -0.6985) (xy -1.524 0.6985)
			)
			(stroke
				(width 0)
				(type default)
			)
			(fill no)
			(layer "F.CrtYd")
		)
		(fp_text user "3"
			(at 0.104902 -2.27965 0)
			(unlocked yes)
			(layer "F.SilkS")
			(effects
				(font
					(size 0.635 0.4064)
					(thickness 0.1524)
				)
			)
		)
		(fp_text user "1"
			(at -1.199896 2.222246 0)
			(unlocked yes)
			(layer "F.SilkS")
			(effects
				(font
					(size 0.635 0.4064)
					(thickness 0.1524)
				)
			)
		)
		(fp_text user "2"
			(at 0.561594 2.27838 0)
			(unlocked yes)
			(layer "F.SilkS")
			(effects
				(font
					(size 0.635 0.4064)
					(thickness 0.1524)
				)
			)
		)
		(pad "1" smd rect
			(at -1.016 1.1176 90)
			(size 1.016 1.27)
			(layers "F.Cu" "F.Mask" "F.Paste")
			(net "GND")
		)
		(pad "2" smd rect
			(at 1.016 1.1176 90)
			(size 1.016 1.27)
			(layers "F.Cu" "F.Mask" "F.Paste")
			(net "P5V_CRT")
		)
		(pad "3" smd rect
			(at 0 -1.1176 90)
			(size 1.016 1.27)
			(layers "F.Cu" "F.Mask" "F.Paste")
			(net "CRT_HSYNC")
		)
	)
	(footprint ""
		(layer "F.Cu")
		(at 48.955452 -170.821604)
		(property "Reference" "C621"
			(at -8.508492 131.261612 0)
			(unlocked yes)
			(layer "F.SilkS")
			(effects
				(font
					(size 0.7874 0.5842)
					(thickness 0.1524)
				)
				(justify left)
			)
		)
		(property "Value" ""
			(at 0 0 0)
			(layer "F.Fab")
			(effects
				(font
					(size 1.27 1.27)
				)
			)
		)
		(duplicate_pad_numbers_are_jumpers no)
		(fp_line
			(start -0.7874 -0.4064)
			(end 0.7874 -0.4064)
			(stroke
				(width 0.1524)
				(type default)
			)
			(layer "F.SilkS")
		)
		(fp_line
			(start -0.7874 0.4064)
			(end -0.7874 -0.4064)
			(stroke
				(width 0.1524)
				(type default)
			)
			(layer "F.SilkS")
		)
		(fp_line
			(start 0 0.381)
			(end 0 -0.381)
			(stroke
				(width 0.1524)
				(type default)
			)
			(layer "F.SilkS")
		)
		(fp_line
			(start 0.7874 -0.4064)
			(end 0.7874 0.4064)
			(stroke
				(width 0.1524)
				(type default)
			)
			(layer "F.SilkS")
		)
		(fp_line
			(start 0.7874 0.4064)
			(end -0.7874 0.4064)
			(stroke
				(width 0.1524)
				(type default)
			)
			(layer "F.SilkS")
		)
		(fp_poly
			(pts
				(xy -0.5334 0.254) (xy -0.635 0.254) (xy -0.635 0.2286) (xy -0.635 -0.254) (xy -0.5334 -0.254) (xy -0.5334 -0.2794)
				(xy 0.5334 -0.2794) (xy 0.5334 -0.254) (xy 0.635 -0.254) (xy 0.635 0.254) (xy 0.5334 0.254) (xy 0.5334 0.2794)
				(xy -0.508 0.2794) (xy -0.5334 0.2794)
			)
			(stroke
				(width 0)
				(type default)
			)
			(fill no)
			(layer "F.CrtYd")
		)
		(pad "1" smd rect
			(at 0.40005 0)
			(size 0.4572 0.508)
			(layers "F.Cu" "F.Mask" "F.Paste")
			(net "P3V3_NODE1")
		)
		(pad "2" smd rect
			(at -0.40005 0)
			(size 0.4572 0.508)
			(layers "F.Cu" "F.Mask" "F.Paste")
			(net "GND")
		)
	)
	(footprint ""
		(layer "F.Cu")
		(at 121.77522 -185.209942 -90)
		(property "Reference" "R866"
			(at -4.768088 -0.152908 90)
			(unlocked yes)
			(layer "F.SilkS")
			(effects
				(font
					(size 0.7874 0.5842)
					(thickness 0.1524)
				)
				(justify left)
			)
		)
		(property "Value" ""
			(at 0 0 270)
			(layer "F.Fab")
			(effects
				(font
					(size 1.27 1.27)
				)
			)
		)
		(duplicate_pad_numbers_are_jumpers no)
		(fp_line
			(start -0.7874 0.4064)
			(end -0.7874 -0.4064)
			(stroke
				(width 0.1524)
				(type default)
			)
			(layer "F.SilkS")
		)
		(fp_line
			(start 0.7874 0.4064)
			(end -0.7874 0.4064)
			(stroke
				(width 0.1524)
				(type default)
			)
			(layer "F.SilkS")
		)
		(fp_line
			(start -0.7874 -0.4064)
			(end 0.7874 -0.4064)
			(stroke
				(width 0.1524)
				(type default)
			)
			(layer "F.SilkS")
		)
		(fp_line
			(start 0.7874 -0.4064)
			(end 0.7874 0.4064)
			(stroke
				(width 0.1524)
				(type default)
			)
			(layer "F.SilkS")
		)
		(fp_poly
			(pts
				(xy -0.508 0.2794) (xy -0.508 0.2286) (xy -0.635 0.2286) (xy -0.635 -0.254) (xy -0.5334 -0.254)
				(xy -0.5334 -0.2794) (xy 0.5334 -0.2794) (xy 0.5334 -0.254) (xy 0.635 -0.254) (xy 0.635 0.254) (xy 0.5334 0.254)
				(xy 0.5334 0.2794)
			)
			(stroke
				(width 0)
				(type default)
			)
			(fill no)
			(layer "F.CrtYd")
		)
		(pad "1" smd rect
			(at 0.40005 0 270)
			(size 0.4572 0.508)
			(layers "F.Cu" "F.Mask" "F.Paste")
			(net "T8_NODE3_EN")
		)
		(pad "2" smd rect
			(at -0.40005 0 270)
			(size 0.4572 0.508)
			(layers "F.Cu" "F.Mask" "F.Paste")
			(net "T8_NODE3_EN_R")
		)
	)
	(footprint ""
		(layer "F.Cu")
		(at 132.03936 -109.869224 90)
		(property "Reference" "R9"
			(at 0.912114 0.22098 90)
			(unlocked yes)
			(layer "F.SilkS")
			(effects
				(font
					(size 0.7874 0.5842)
					(thickness 0.1524)
				)
				(justify left)
			)
		)
		(property "Value" ""
			(at 0 0 90)
			(layer "F.Fab")
			(effects
				(font
					(size 1.27 1.27)
				)
			)
		)
		(duplicate_pad_numbers_are_jumpers no)
		(fp_line
			(start 0.7874 -0.4064)
			(end 0.7874 0.4064)
			(stroke
				(width 0.1524)
				(type default)
			)
			(layer "F.SilkS")
		)
		(fp_line
			(start -0.7874 -0.4064)
			(end 0.7874 -0.4064)
			(stroke
				(width 0.1524)
				(type default)
			)
			(layer "F.SilkS")
		)
		(fp_line
			(start 0.7874 0.4064)
			(end -0.7874 0.4064)
			(stroke
				(width 0.1524)
				(type default)
			)
			(layer "F.SilkS")
		)
		(fp_line
			(start -0.7874 0.4064)
			(end -0.7874 -0.4064)
			(stroke
				(width 0.1524)
				(type default)
			)
			(layer "F.SilkS")
		)
		(fp_poly
			(pts
				(xy -0.508 0.2794) (xy -0.508 0.2286) (xy -0.635 0.2286) (xy -0.635 -0.254) (xy -0.5334 -0.254)
				(xy -0.5334 -0.2794) (xy 0.5334 -0.2794) (xy 0.5334 -0.254) (xy 0.635 -0.254) (xy 0.635 0.254) (xy 0.5334 0.254)
				(xy 0.5334 0.2794)
			)
			(stroke
				(width 0)
				(type default)
			)
			(fill no)
			(layer "F.CrtYd")
		)
		(pad "1" smd rect
			(at 0.40005 0 90)
			(size 0.4572 0.508)
			(layers "F.Cu" "F.Mask" "F.Paste")
			(net "CLK_25M_SATA_NODE1_R")
		)
		(pad "2" smd rect
			(at -0.40005 0 90)
			(size 0.4572 0.508)
			(layers "F.Cu" "F.Mask" "F.Paste")
			(net "CLK_25M_SATA_NODE1")
		)
	)
)
